(kicad_pcb
	(version 20260206)
	(generator "pcbnew")
	(generator_version "10.0")
	(general
		(thickness 1.6)
		(legacy_teardrops no)
	)
	(paper "A4")
	(title_block
		(title "Bryce Canyon_R.DPB_16317-1_OCP.brd")
		(comment 1 "Bryce Canyon / footprints 628-634 of 2099")
	)
	(layers
		(0 "F.Cu" signal "TOP")
		(4 "In1.Cu" signal "L2GND")
		(6 "In2.Cu" signal "L3")
		(8 "In3.Cu" signal "L4VCC")
		(10 "In4.Cu" signal "L5VCC")
		(12 "In5.Cu" signal "L6")
		(14 "In6.Cu" signal "L7GND")
		(2 "B.Cu" signal "BOTTOM")
		(9 "F.Adhes" user "F.Adhesive")
		(11 "B.Adhes" user "B.Adhesive")
		(13 "F.Paste" user "Package Geometry/Pastemask Top")
		(15 "B.Paste" user "Package Geometry/Pastemask Bottom")
		(5 "F.SilkS" user "Ref Des/Silkscreen Top")
		(7 "B.SilkS" user "Ref Des/Silkscreen Bottom")
		(1 "F.Mask" user "Board Geometry/Soldermask Top")
		(3 "B.Mask" user "Board Geometry/Soldermask Bottom")
		(17 "Dwgs.User" user "User.Drawings")
		(19 "Cmts.User" user "User.Comments")
		(21 "Eco1.User" user "User.Eco1")
		(23 "Eco2.User" user "User.Eco2")
		(25 "Edge.Cuts" user "Board Geometry/Outline")
		(27 "Margin" user)
		(31 "F.CrtYd" user "Package Geometry/Place Bound Top")
		(29 "B.CrtYd" user "Package Geometry/Place Bound Bottom")
		(35 "F.Fab" user "Ref Des/Assembly Top")
		(33 "B.Fab" user "Ref Des/Assembly Bottom")
	)
	(footprint ""
		(layer "F.Cu")
		(at 127.113284 -15.219426 90)
		(property "Reference" "C379"
			(at 0 0 90)
			(layer "F.SilkS")
			(hide yes)
			(effects
				(font
					(size 1.27 1.27)
				)
			)
		)
		(property "Value" "SCD01U16V1KX-GP"
			(at -2.8321 -1.7399 90)
			(unlocked yes)
			(layer "F.Fab")
			(hide yes)
			(effects
				(font
					(size 1.016 1.016)
					(thickness 0.1524)
				)
			)
		)
		(property "Device Type" "C0201H13"
			(at -2.8321 -3.2639 90)
			(unlocked yes)
			(layer "F.Fab")
			(hide yes)
			(effects
				(font
					(size 1.016 1.016)
					(thickness 0.1524)
				)
			)
		)
		(duplicate_pad_numbers_are_jumpers no)
		(fp_rect
			(start -0.2794 0.6477)
			(end 0.2794 -0.6477)
			(stroke
				(width 0)
				(type default)
			)
			(fill no)
			(layer "F.CrtYd")
		)
		(fp_rect
			(start -0.2794 0.6477)
			(end 0.2794 -0.6477)
			(stroke
				(width 0)
				(type default)
			)
			(fill no)
			(layer "F.Fab")
		)
		(pad "1" smd custom
			(at 0 -0.2794 90)
			(size 0.0762 0.0762)
			(layers "F.Cu" "F.Mask" "F.Paste")
			(net "SAS_HDD_RX_N27")
			(options
				(clearance outline)
				(anchor circle)
			)
			(primitives
				(gr_poly
					(pts
						(arc
							(start 0.1524 -0.127)
							(mid 0.137521 -0.162921)
							(end 0.1016 -0.1778)
						)
						(arc
							(start -0.1016 -0.1778)
							(mid -0.137521 -0.162921)
							(end -0.1524 -0.127)
						)
						(arc
							(start -0.1524 0.127)
							(mid -0.137521 0.162921)
							(end -0.1016 0.1778)
						)
						(arc
							(start 0.1016 0.1778)
							(mid 0.137521 0.162921)
							(end 0.1524 0.127)
						)
					)
					(width 0)
					(fill yes)
				)
			)
		)
		(pad "2" smd custom
			(at 0 0.2794 90)
			(size 0.0762 0.0762)
			(layers "F.Cu" "F.Mask" "F.Paste")
			(net "PHY_SCC_B_TO_DRV_B_27_DN")
			(options
				(clearance outline)
				(anchor circle)
			)
			(primitives
				(gr_poly
					(pts
						(arc
							(start 0.1524 -0.127)
							(mid 0.137521 -0.162921)
							(end 0.1016 -0.1778)
						)
						(arc
							(start -0.1016 -0.1778)
							(mid -0.137521 -0.162921)
							(end -0.1524 -0.127)
						)
						(arc
							(start -0.1524 0.127)
							(mid -0.137521 0.162921)
							(end -0.1016 0.1778)
						)
						(arc
							(start 0.1016 0.1778)
							(mid 0.137521 0.162921)
							(end 0.1524 0.127)
						)
					)
					(width 0)
					(fill yes)
				)
			)
		)
	)
	(footprint ""
		(layer "F.Cu")
		(at 478.409 -8.382 180)
		(property "Reference" "Q185"
			(at 0 0 180)
			(layer "F.SilkS")
			(hide yes)
			(effects
				(font
					(size 1.27 1.27)
				)
			)
		)
		(property "Value" "2N7002KDW-GP"
			(at -2.3622 -8.2042 180)
			(unlocked yes)
			(layer "F.Fab")
			(hide yes)
			(effects
				(font
					(size 1.016 1.016)
					(thickness 0.1524)
				)
			)
		)
		(property "Device Type" "SOT-363H44"
			(at -2.3622 -10.1092 180)
			(unlocked yes)
			(layer "F.Fab")
			(hide yes)
			(effects
				(font
					(size 1.016 1.016)
					(thickness 0.1524)
				)
			)
		)
		(duplicate_pad_numbers_are_jumpers no)
		(fp_line
			(start 1.4478 1.7018)
			(end 1.4478 -1.7018)
			(stroke
				(width 0.1524)
				(type default)
			)
			(layer "F.SilkS")
		)
		(fp_line
			(start 1.4478 -1.7018)
			(end -1.4478 -1.7018)
			(stroke
				(width 0.1524)
				(type default)
			)
			(layer "F.SilkS")
		)
		(fp_line
			(start -1.27 1.524)
			(end -1.27 0.6604)
			(stroke
				(width 0.4826)
				(type default)
			)
			(layer "F.SilkS")
		)
		(fp_line
			(start -1.4478 1.7018)
			(end 1.4478 1.7018)
			(stroke
				(width 0.1524)
				(type default)
			)
			(layer "F.SilkS")
		)
		(fp_line
			(start -1.4478 -1.7018)
			(end -1.4478 1.7018)
			(stroke
				(width 0.1524)
				(type default)
			)
			(layer "F.SilkS")
		)
		(fp_poly
			(pts
				(xy -1.524 -1.778) (xy 1.524 -1.778) (xy 1.524 1.778) (xy -1.524 1.778)
			)
			(stroke
				(width 0)
				(type default)
			)
			(fill no)
			(layer "F.CrtYd")
		)
		(fp_poly
			(pts
				(xy -1.524 -1.778) (xy 1.524 -1.778) (xy 1.524 1.778) (xy -1.524 1.778)
			)
			(stroke
				(width 0)
				(type default)
			)
			(fill no)
			(layer "F.Fab")
		)
		(pad "1" smd rect
			(at -0.65024 0.9398 180)
			(size 0.4064 1.016)
			(layers "F.Cu" "F.Mask" "F.Paste")
			(net "GND")
		)
		(pad "2" smd rect
			(at 0 0.9398 180)
			(size 0.4064 1.016)
			(layers "F.Cu" "F.Mask" "F.Paste")
			(net "SW_PWR_R_HDD35")
		)
		(pad "3" smd rect
			(at 0.65024 0.9398 180)
			(size 0.4064 1.016)
			(layers "F.Cu" "F.Mask" "F.Paste")
			(net "SW_HDD_P35")
		)
		(pad "4" smd rect
			(at 0.65024 -0.9398 180)
			(size 0.4064 1.016)
			(layers "F.Cu" "F.Mask" "F.Paste")
			(net "GND")
		)
		(pad "5" smd rect
			(at 0 -0.9398 180)
			(size 0.4064 1.016)
			(layers "F.Cu" "F.Mask" "F.Paste")
			(net "SW_HDD_G35")
		)
		(pad "6" smd rect
			(at -0.65024 -0.9398 180)
			(size 0.4064 1.016)
			(layers "F.Cu" "F.Mask" "F.Paste")
			(net "SW_HDD_R35")
		)
	)
	(footprint ""
		(layer "F.Cu")
		(at 87.376 -45.466 180)
		(property "Reference" "C374"
			(at 0 0 180)
			(layer "F.SilkS")
			(hide yes)
			(effects
				(font
					(size 1.27 1.27)
				)
			)
		)
		(property "Value" "SC1U25V3KX-GP"
			(at 0 -2.8194 180)
			(unlocked yes)
			(layer "F.Fab")
			(hide yes)
			(effects
				(font
					(size 1.016 1.016)
					(thickness 0.1524)
				)
			)
		)
		(property "Device Type" "C603H36"
			(at 0 -4.3434 180)
			(unlocked yes)
			(layer "F.Fab")
			(hide yes)
			(effects
				(font
					(size 1.016 1.016)
					(thickness 0.1524)
				)
			)
		)
		(duplicate_pad_numbers_are_jumpers no)
		(fp_line
			(start 0.508 0)
			(end -0.508 0)
			(stroke
				(width 0.2032)
				(type default)
			)
			(layer "F.SilkS")
		)
		(fp_rect
			(start -0.5842 1.3335)
			(end 0.5842 -1.3335)
			(stroke
				(width 0)
				(type default)
			)
			(fill no)
			(layer "F.CrtYd")
		)
		(fp_rect
			(start -0.5842 1.3335)
			(end 0.5842 -1.3335)
			(stroke
				(width 0)
				(type default)
			)
			(fill no)
			(layer "F.Fab")
		)
		(pad "1" smd custom
			(at 0 -0.762 180)
			(size 0.2159 0.2159)
			(layers "F.Cu" "F.Mask" "F.Paste")
			(net "P12V_HDD26")
			(options
				(clearance outline)
				(anchor circle)
			)
			(primitives
				(gr_poly
					(pts
						(arc
							(start -0.3302 -0.4318)
							(mid -0.402042 -0.402042)
							(end -0.4318 -0.3302)
						)
						(arc
							(start -0.4318 0.3302)
							(mid -0.402042 0.402042)
							(end -0.3302 0.4318)
						)
						(arc
							(start 0.3302 0.4318)
							(mid 0.402042 0.402042)
							(end 0.4318 0.3302)
						)
						(arc
							(start 0.4318 -0.3302)
							(mid 0.402042 -0.402042)
							(end 0.3302 -0.4318)
						)
					)
					(width 0)
					(fill yes)
				)
			)
		)
		(pad "2" smd custom
			(at 0 0.762 180)
			(size 0.2159 0.2159)
			(layers "F.Cu" "F.Mask" "F.Paste")
			(net "GND")
			(options
				(clearance outline)
				(anchor circle)
			)
			(primitives
				(gr_poly
					(pts
						(arc
							(start -0.3302 -0.4318)
							(mid -0.402042 -0.402042)
							(end -0.4318 -0.3302)
						)
						(arc
							(start -0.4318 0.3302)
							(mid -0.402042 0.402042)
							(end -0.3302 0.4318)
						)
						(arc
							(start 0.3302 0.4318)
							(mid 0.402042 0.402042)
							(end 0.4318 0.3302)
						)
						(arc
							(start 0.4318 -0.3302)
							(mid 0.402042 -0.402042)
							(end 0.3302 -0.4318)
						)
					)
					(width 0)
					(fill yes)
				)
			)
		)
	)
	(footprint ""
		(layer "F.Cu")
		(at 112.8776 -9.525)
		(property "Reference" "R706"
			(at 0 0 0)
			(layer "F.SilkS")
			(hide yes)
			(effects
				(font
					(size 1.27 1.27)
				)
			)
		)
		(property "Value" "300KR2F-GP"
			(at 0.064008 -3.993896 0)
			(unlocked yes)
			(layer "F.Fab")
			(hide yes)
			(effects
				(font
					(size 1.016 1.016)
					(thickness 0.1524)
				)
			)
		)
		(property "Device Type" "R402H16"
			(at 0.064008 -5.517896 0)
			(unlocked yes)
			(layer "F.Fab")
			(hide yes)
			(effects
				(font
					(size 1.016 1.016)
					(thickness 0.1524)
				)
			)
		)
		(duplicate_pad_numbers_are_jumpers no)
		(fp_line
			(start -0.508 -0.9398)
			(end -0.508 0.9398)
			(stroke
				(width 0.1524)
				(type default)
			)
			(layer "F.SilkS")
		)
		(fp_line
			(start 0.508 -0.9398)
			(end -0.508 -0.9398)
			(stroke
				(width 0.1524)
				(type default)
			)
			(layer "F.SilkS")
		)
		(fp_rect
			(start -0.508 0.9398)
			(end 0.508 -0.9398)
			(stroke
				(width 0)
				(type default)
			)
			(fill no)
			(layer "F.CrtYd")
		)
		(fp_rect
			(start -0.508 0.9398)
			(end 0.508 -0.9398)
			(stroke
				(width 0)
				(type default)
			)
			(fill no)
			(layer "F.Fab")
		)
		(pad "1" smd custom
			(at 0 -0.4445)
			(size 0.1397 0.1397)
			(layers "F.Cu" "F.Mask" "F.Paste")
			(net "SW_HDD_N27")
			(options
				(clearance outline)
				(anchor circle)
			)
			(primitives
				(gr_poly
					(pts
						(arc
							(start -0.1778 -0.2794)
							(mid -0.249642 -0.249642)
							(end -0.2794 -0.1778)
						)
						(arc
							(start -0.2794 0.1778)
							(mid -0.249642 0.249642)
							(end -0.1778 0.2794)
						)
						(arc
							(start 0.1778 0.2794)
							(mid 0.249642 0.249642)
							(end 0.2794 0.1778)
						)
						(arc
							(start 0.2794 -0.1778)
							(mid 0.249642 -0.249642)
							(end 0.1778 -0.2794)
						)
					)
					(width 0)
					(fill yes)
				)
			)
		)
		(pad "2" smd custom
			(at 0 0.4445)
			(size 0.1397 0.1397)
			(layers "F.Cu" "F.Mask" "F.Paste")
			(net "P12V_B")
			(options
				(clearance outline)
				(anchor circle)
			)
			(primitives
				(gr_poly
					(pts
						(arc
							(start -0.1778 -0.2794)
							(mid -0.249642 -0.249642)
							(end -0.2794 -0.1778)
						)
						(arc
							(start -0.2794 0.1778)
							(mid -0.249642 0.249642)
							(end -0.1778 0.2794)
						)
						(arc
							(start 0.1778 0.2794)
							(mid 0.249642 0.249642)
							(end 0.2794 0.1778)
						)
						(arc
							(start 0.2794 -0.1778)
							(mid 0.249642 -0.249642)
							(end 0.1778 -0.2794)
						)
					)
					(width 0)
					(fill yes)
				)
			)
		)
	)
	(footprint ""
		(layer "F.Cu")
		(at 472.313 -214.249)
		(property "Reference" "R375"
			(at 0 0 0)
			(layer "F.SilkS")
			(hide yes)
			(effects
				(font
					(size 1.27 1.27)
				)
			)
		)
		(property "Value" "130R3F-GP"
			(at -0.0254 -2.5146 0)
			(unlocked yes)
			(layer "F.Fab")
			(hide yes)
			(effects
				(font
					(size 1.016 1.016)
					(thickness 0.1524)
				)
			)
		)
		(property "Device Type" "R603H22"
			(at -0.0254 -4.0386 0)
			(unlocked yes)
			(layer "F.Fab")
			(hide yes)
			(effects
				(font
					(size 1.016 1.016)
					(thickness 0.1524)
				)
			)
		)
		(duplicate_pad_numbers_are_jumpers no)
		(fp_line
			(start -0.4826 0)
			(end -0.2032 0)
			(stroke
				(width 0.2032)
				(type default)
			)
			(layer "F.SilkS")
		)
		(fp_line
			(start 0.2032 0)
			(end 0.4826 0)
			(stroke
				(width 0.2032)
				(type default)
			)
			(layer "F.SilkS")
		)
		(fp_rect
			(start -0.5842 1.3335)
			(end 0.5842 -1.3335)
			(stroke
				(width 0)
				(type default)
			)
			(fill no)
			(layer "F.CrtYd")
		)
		(fp_rect
			(start -0.5842 1.3335)
			(end 0.5842 -1.3335)
			(stroke
				(width 0)
				(type default)
			)
			(fill no)
			(layer "F.Fab")
		)
		(pad "1" smd custom
			(at 0 -0.762)
			(size 0.2159 0.2159)
			(layers "F.Cu" "F.Mask" "F.Paste")
			(net "P5V_B_3")
			(options
				(clearance outline)
				(anchor circle)
			)
			(primitives
				(gr_poly
					(pts
						(arc
							(start -0.3302 -0.4318)
							(mid -0.402042 -0.402042)
							(end -0.4318 -0.3302)
						)
						(arc
							(start -0.4318 0.3302)
							(mid -0.402042 0.402042)
							(end -0.3302 0.4318)
						)
						(arc
							(start 0.3302 0.4318)
							(mid 0.402042 0.402042)
							(end 0.4318 0.3302)
						)
						(arc
							(start 0.4318 -0.3302)
							(mid 0.402042 -0.402042)
							(end 0.3302 -0.4318)
						)
					)
					(width 0)
					(fill yes)
				)
			)
		)
		(pad "2" smd custom
			(at 0 0.762)
			(size 0.2159 0.2159)
			(layers "F.Cu" "F.Mask" "F.Paste")
			(net "FLT_HDD11")
			(options
				(clearance outline)
				(anchor circle)
			)
			(primitives
				(gr_poly
					(pts
						(arc
							(start -0.3302 -0.4318)
							(mid -0.402042 -0.402042)
							(end -0.4318 -0.3302)
						)
						(arc
							(start -0.4318 0.3302)
							(mid -0.402042 0.402042)
							(end -0.3302 0.4318)
						)
						(arc
							(start 0.3302 0.4318)
							(mid 0.402042 0.402042)
							(end 0.4318 0.3302)
						)
						(arc
							(start 0.4318 -0.3302)
							(mid 0.402042 -0.402042)
							(end 0.3302 -0.4318)
						)
					)
					(width 0)
					(fill yes)
				)
			)
		)
	)
	(footprint ""
		(layer "F.Cu")
		(at 141.28115 -102.427786 -90)
		(property "Reference" "R389"
			(at 0 0 270)
			(layer "F.SilkS")
			(hide yes)
			(effects
				(font
					(size 1.27 1.27)
				)
			)
		)
		(property "Value" "4K7R2F-GP"
			(at 0.064008 -3.993896 270)
			(unlocked yes)
			(layer "F.Fab")
			(hide yes)
			(effects
				(font
					(size 1.016 1.016)
					(thickness 0.1524)
				)
			)
		)
		(property "Device Type" "R402H16"
			(at 0.064008 -5.517896 270)
			(unlocked yes)
			(layer "F.Fab")
			(hide yes)
			(effects
				(font
					(size 1.016 1.016)
					(thickness 0.1524)
				)
			)
		)
		(duplicate_pad_numbers_are_jumpers no)
		(fp_line
			(start -0.508 -0.9398)
			(end -0.508 0.9398)
			(stroke
				(width 0.1524)
				(type default)
			)
			(layer "F.SilkS")
		)
		(fp_line
			(start 0.508 -0.9398)
			(end -0.508 -0.9398)
			(stroke
				(width 0.1524)
				(type default)
			)
			(layer "F.SilkS")
		)
		(fp_rect
			(start -0.508 0.9398)
			(end 0.508 -0.9398)
			(stroke
				(width 0)
				(type default)
			)
			(fill no)
			(layer "F.CrtYd")
		)
		(fp_rect
			(start -0.508 0.9398)
			(end 0.508 -0.9398)
			(stroke
				(width 0)
				(type default)
			)
			(fill no)
			(layer "F.Fab")
		)
		(pad "1" smd custom
			(at 0 -0.4445 270)
			(size 0.1397 0.1397)
			(layers "F.Cu" "F.Mask" "F.Paste")
			(net "DRIVE_B_16_FLT_LED")
			(options
				(clearance outline)
				(anchor circle)
			)
			(primitives
				(gr_poly
					(pts
						(arc
							(start -0.1778 -0.2794)
							(mid -0.249642 -0.249642)
							(end -0.2794 -0.1778)
						)
						(arc
							(start -0.2794 0.1778)
							(mid -0.249642 0.249642)
							(end -0.1778 0.2794)
						)
						(arc
							(start 0.1778 0.2794)
							(mid 0.249642 0.249642)
							(end 0.2794 0.1778)
						)
						(arc
							(start 0.2794 -0.1778)
							(mid 0.249642 -0.249642)
							(end 0.1778 -0.2794)
						)
					)
					(width 0)
					(fill yes)
				)
			)
		)
		(pad "2" smd custom
			(at 0 0.4445 270)
			(size 0.1397 0.1397)
			(layers "F.Cu" "F.Mask" "F.Paste")
			(net "GND")
			(options
				(clearance outline)
				(anchor circle)
			)
			(primitives
				(gr_poly
					(pts
						(arc
							(start -0.1778 -0.2794)
							(mid -0.249642 -0.249642)
							(end -0.2794 -0.1778)
						)
						(arc
							(start -0.2794 0.1778)
							(mid -0.249642 0.249642)
							(end -0.1778 0.2794)
						)
						(arc
							(start 0.1778 0.2794)
							(mid 0.249642 0.249642)
							(end 0.2794 0.1778)
						)
						(arc
							(start 0.2794 -0.1778)
							(mid 0.249642 -0.249642)
							(end 0.1778 -0.2794)
						)
					)
					(width 0)
					(fill yes)
				)
			)
		)
	)
	(footprint ""
		(layer "F.Cu")
		(at 244.662452 -359.617772 180)
		(property "Reference" "R1050"
			(at 0 0 180)
			(layer "F.SilkS")
			(hide yes)
			(effects
				(font
					(size 1.27 1.27)
				)
			)
		)
		(property "Value" "3K92R2F-GP"
			(at 0.064008 -3.993896 180)
			(unlocked yes)
			(layer "F.Fab")
			(hide yes)
			(effects
				(font
					(size 1.016 1.016)
					(thickness 0.1524)
				)
			)
		)
		(property "Device Type" "R402H16"
			(at 0.064008 -5.517896 180)
			(unlocked yes)
			(layer "F.Fab")
			(hide yes)
			(effects
				(font
					(size 1.016 1.016)
					(thickness 0.1524)
				)
			)
		)
		(duplicate_pad_numbers_are_jumpers no)
		(fp_line
			(start 0.508 -0.9398)
			(end -0.508 -0.9398)
			(stroke
				(width 0.1524)
				(type default)
			)
			(layer "F.SilkS")
		)
		(fp_line
			(start -0.508 -0.9398)
			(end -0.508 0.9398)
			(stroke
				(width 0.1524)
				(type default)
			)
			(layer "F.SilkS")
		)
		(fp_rect
			(start -0.508 0.9398)
			(end 0.508 -0.9398)
			(stroke
				(width 0)
				(type default)
			)
			(fill no)
			(layer "F.CrtYd")
		)
		(fp_rect
			(start -0.508 0.9398)
			(end 0.508 -0.9398)
			(stroke
				(width 0)
				(type default)
			)
			(fill no)
			(layer "F.Fab")
		)
		(pad "1" smd custom
			(at 0 -0.4445 180)
			(size 0.1397 0.1397)
			(layers "F.Cu" "F.Mask" "F.Paste")
			(net "MB3_CM_OV_R")
			(options
				(clearance outline)
				(anchor circle)
			)
			(primitives
				(gr_poly
					(pts
						(arc
							(start -0.1778 -0.2794)
							(mid -0.249642 -0.249642)
							(end -0.2794 -0.1778)
						)
						(arc
							(start -0.2794 0.1778)
							(mid -0.249642 0.249642)
							(end -0.1778 0.2794)
						)
						(arc
							(start 0.1778 0.2794)
							(mid 0.249642 0.249642)
							(end 0.2794 0.1778)
						)
						(arc
							(start 0.2794 -0.1778)
							(mid 0.249642 -0.249642)
							(end 0.1778 -0.2794)
						)
					)
					(width 0)
					(fill yes)
				)
			)
		)
		(pad "2" smd custom
			(at 0 0.4445 180)
			(size 0.1397 0.1397)
			(layers "F.Cu" "F.Mask" "F.Paste")
			(net "AGND_CURRENT_DPB")
			(options
				(clearance outline)
				(anchor circle)
			)
			(primitives
				(gr_poly
					(pts
						(arc
							(start -0.1778 -0.2794)
							(mid -0.249642 -0.249642)
							(end -0.2794 -0.1778)
						)
						(arc
							(start -0.2794 0.1778)
							(mid -0.249642 0.249642)
							(end -0.1778 0.2794)
						)
						(arc
							(start 0.1778 0.2794)
							(mid 0.249642 0.249642)
							(end 0.2794 0.1778)
						)
						(arc
							(start 0.2794 -0.1778)
							(mid 0.249642 -0.249642)
							(end 0.1778 -0.2794)
						)
					)
					(width 0)
					(fill yes)
				)
			)
		)
	)
)
